(kicad_pcb
	(version 20260206)
	(generator "pcbnew")
	(generator_version "10.0")
	(general
		(thickness 1.6)
		(legacy_teardrops no)
	)
	(paper "A4")
	(title_block
		(title "Bryce Canyon_IOM_IOC_16318-2_OCP.brd")
		(comment 1 "Bryce Canyon / footprints 1282-1288 of 1605")
	)
	(layers
		(0 "F.Cu" signal "TOP")
		(4 "In1.Cu" signal "L2GND")
		(6 "In2.Cu" signal "L3")
		(8 "In3.Cu" signal "L4VCC")
		(10 "In4.Cu" signal "L5VCC")
		(12 "In5.Cu" signal "L6")
		(14 "In6.Cu" signal "L7GND")
		(2 "B.Cu" signal "BOTTOM")
		(9 "F.Adhes" user "F.Adhesive")
		(11 "B.Adhes" user "B.Adhesive")
		(13 "F.Paste" user "Package Geometry/Pastemask Top")
		(15 "B.Paste" user "Package Geometry/Pastemask Bottom")
		(5 "F.SilkS" user "Ref Des/Silkscreen Top")
		(7 "B.SilkS" user "Ref Des/Silkscreen Bottom")
		(1 "F.Mask" user "Board Geometry/Soldermask Top")
		(3 "B.Mask" user "Board Geometry/Soldermask Bottom")
		(17 "Dwgs.User" user "User.Drawings")
		(19 "Cmts.User" user "User.Comments")
		(21 "Eco1.User" user "User.Eco1")
		(23 "Eco2.User" user "User.Eco2")
		(25 "Edge.Cuts" user "Board Geometry/Outline")
		(27 "Margin" user)
		(31 "F.CrtYd" user "Package Geometry/Place Bound Top")
		(29 "B.CrtYd" user "Package Geometry/Place Bound Bottom")
		(35 "F.Fab" user "Ref Des/Assembly Top")
		(33 "B.Fab" user "Ref Des/Assembly Bottom")
	)
	(footprint ""
		(layer "B.Cu")
		(at 116.3828 -15.7226 90)
		(property "Reference" "R744"
			(at 0 0 90)
			(layer "B.SilkS")
			(hide yes)
			(effects
				(font
					(size 1.27 1.27)
				)
				(justify mirror)
			)
		)
		(property "Value" "11KR2F-L-GP"
			(at -0.064008 -3.993896 90)
			(unlocked yes)
			(layer "B.Fab")
			(hide yes)
			(effects
				(font
					(size 1.016 1.016)
					(thickness 0.1524)
				)
				(justify mirror)
			)
		)
		(property "Device Type" "R402H16"
			(at -0.064008 -5.517896 90)
			(unlocked yes)
			(layer "B.Fab")
			(hide yes)
			(effects
				(font
					(size 1.016 1.016)
					(thickness 0.1524)
				)
				(justify mirror)
			)
		)
		(duplicate_pad_numbers_are_jumpers no)
		(fp_line
			(start 0.508 -0.9398)
			(end 0.508 0.9398)
			(stroke
				(width 0.1524)
				(type default)
			)
			(layer "B.SilkS")
		)
		(fp_line
			(start -0.508 -0.9398)
			(end 0.508 -0.9398)
			(stroke
				(width 0.1524)
				(type default)
			)
			(layer "B.SilkS")
		)
		(fp_rect
			(start 0.508 0.9398)
			(end -0.508 -0.9398)
			(stroke
				(width 0)
				(type default)
			)
			(fill no)
			(layer "B.CrtYd")
		)
		(fp_rect
			(start 0.508 0.9398)
			(end -0.508 -0.9398)
			(stroke
				(width 0)
				(type default)
			)
			(fill no)
			(layer "B.Fab")
		)
		(pad "1" smd custom
			(at 0 -0.4445 270)
			(size 0.1397 0.1397)
			(layers "B.Cu" "B.Mask" "B.Paste")
			(net "IOM_ADM1278_EN")
			(options
				(clearance outline)
				(anchor circle)
			)
			(primitives
				(gr_poly
					(pts
						(arc
							(start -0.1778 0.2794)
							(mid -0.249642 0.249642)
							(end -0.2794 0.1778)
						)
						(arc
							(start -0.2794 -0.1778)
							(mid -0.249642 -0.249642)
							(end -0.1778 -0.2794)
						)
						(arc
							(start 0.1778 -0.2794)
							(mid 0.249642 -0.249642)
							(end 0.2794 -0.1778)
						)
						(arc
							(start 0.2794 0.1778)
							(mid 0.249642 0.249642)
							(end 0.1778 0.2794)
						)
					)
					(width 0)
					(fill yes)
				)
			)
		)
		(pad "2" smd custom
			(at 0 0.4445 270)
			(size 0.1397 0.1397)
			(layers "B.Cu" "B.Mask" "B.Paste")
			(net "GND")
			(options
				(clearance outline)
				(anchor circle)
			)
			(primitives
				(gr_poly
					(pts
						(arc
							(start -0.1778 0.2794)
							(mid -0.249642 0.249642)
							(end -0.2794 0.1778)
						)
						(arc
							(start -0.2794 -0.1778)
							(mid -0.249642 -0.249642)
							(end -0.1778 -0.2794)
						)
						(arc
							(start 0.1778 -0.2794)
							(mid 0.249642 -0.249642)
							(end 0.2794 -0.1778)
						)
						(arc
							(start 0.2794 0.1778)
							(mid 0.249642 0.249642)
							(end 0.1778 0.2794)
						)
					)
					(width 0)
					(fill yes)
				)
			)
		)
	)
	(footprint ""
		(layer "B.Cu")
		(at 189.983872 -74.793856 90)
		(property "Reference" "C450"
			(at 0 0 90)
			(layer "B.SilkS")
			(hide yes)
			(effects
				(font
					(size 1.27 1.27)
				)
				(justify mirror)
			)
		)
		(property "Value" "SCD1U16V2KX-3GP"
			(at -1.1811 -2.7051 90)
			(unlocked yes)
			(layer "B.Fab")
			(hide yes)
			(effects
				(font
					(size 1.016 1.016)
					(thickness 0.1524)
				)
				(justify mirror)
			)
		)
		(property "Device Type" "C402H22"
			(at -1.1811 -4.2291 90)
			(unlocked yes)
			(layer "B.Fab")
			(hide yes)
			(effects
				(font
					(size 1.016 1.016)
					(thickness 0.1524)
				)
				(justify mirror)
			)
		)
		(duplicate_pad_numbers_are_jumpers no)
		(fp_rect
			(start 0.4318 0.9525)
			(end -0.4318 -0.9525)
			(stroke
				(width 0)
				(type default)
			)
			(fill no)
			(layer "B.CrtYd")
		)
		(fp_rect
			(start 0.4318 0.9525)
			(end -0.4318 -0.9525)
			(stroke
				(width 0)
				(type default)
			)
			(fill no)
			(layer "B.Fab")
		)
		(pad "1" smd custom
			(at 0 -0.4445 270)
			(size 0.1524 0.1524)
			(layers "B.Cu" "B.Mask" "B.Paste")
			(net "P1V8")
			(options
				(clearance outline)
				(anchor circle)
			)
			(primitives
				(gr_poly
					(pts
						(arc
							(start 0.3048 0.2032)
							(mid 0.275042 0.275042)
							(end 0.2032 0.3048)
						)
						(arc
							(start -0.2032 0.3048)
							(mid -0.275042 0.275042)
							(end -0.3048 0.2032)
						)
						(arc
							(start -0.3048 -0.2032)
							(mid -0.275042 -0.275042)
							(end -0.2032 -0.3048)
						)
						(arc
							(start 0.2032 -0.3048)
							(mid 0.275042 -0.275042)
							(end 0.3048 -0.2032)
						)
					)
					(width 0)
					(fill yes)
				)
			)
		)
		(pad "2" smd custom
			(at 0 0.4445 270)
			(size 0.1524 0.1524)
			(layers "B.Cu" "B.Mask" "B.Paste")
			(net "GND")
			(options
				(clearance outline)
				(anchor circle)
			)
			(primitives
				(gr_poly
					(pts
						(arc
							(start 0.3048 0.2032)
							(mid 0.275042 0.275042)
							(end 0.2032 0.3048)
						)
						(arc
							(start -0.2032 0.3048)
							(mid -0.275042 0.275042)
							(end -0.3048 0.2032)
						)
						(arc
							(start -0.3048 -0.2032)
							(mid -0.275042 -0.275042)
							(end -0.2032 -0.3048)
						)
						(arc
							(start 0.2032 -0.3048)
							(mid 0.275042 -0.275042)
							(end 0.3048 -0.2032)
						)
					)
					(width 0)
					(fill yes)
				)
			)
		)
	)
	(footprint ""
		(layer "B.Cu")
		(at 59.055 -133.985 180)
		(property "Reference" "R784"
			(at 0 0 0)
			(layer "B.SilkS")
			(hide yes)
			(effects
				(font
					(size 1.27 1.27)
				)
				(justify mirror)
			)
		)
		(property "Value" "10KR2F-2-GP"
			(at -0.064008 -3.993896 180)
			(unlocked yes)
			(layer "B.Fab")
			(hide yes)
			(effects
				(font
					(size 1.016 1.016)
					(thickness 0.1524)
				)
				(justify mirror)
			)
		)
		(property "Device Type" "R402H16"
			(at -0.064008 -5.517896 180)
			(unlocked yes)
			(layer "B.Fab")
			(hide yes)
			(effects
				(font
					(size 1.016 1.016)
					(thickness 0.1524)
				)
				(justify mirror)
			)
		)
		(duplicate_pad_numbers_are_jumpers no)
		(fp_line
			(start 0.508 -0.9398)
			(end 0.508 0.9398)
			(stroke
				(width 0.1524)
				(type default)
			)
			(layer "B.SilkS")
		)
		(fp_line
			(start -0.508 -0.9398)
			(end 0.508 -0.9398)
			(stroke
				(width 0.1524)
				(type default)
			)
			(layer "B.SilkS")
		)
		(fp_rect
			(start 0.508 0.9398)
			(end -0.508 -0.9398)
			(stroke
				(width 0)
				(type default)
			)
			(fill no)
			(layer "B.CrtYd")
		)
		(fp_rect
			(start 0.508 0.9398)
			(end -0.508 -0.9398)
			(stroke
				(width 0)
				(type default)
			)
			(fill no)
			(layer "B.Fab")
		)
		(pad "1" smd custom
			(at 0 -0.4445)
			(size 0.1397 0.1397)
			(layers "B.Cu" "B.Mask" "B.Paste")
			(net "P3V3_STBY")
			(options
				(clearance outline)
				(anchor circle)
			)
			(primitives
				(gr_poly
					(pts
						(arc
							(start -0.1778 0.2794)
							(mid -0.249642 0.249642)
							(end -0.2794 0.1778)
						)
						(arc
							(start -0.2794 -0.1778)
							(mid -0.249642 -0.249642)
							(end -0.1778 -0.2794)
						)
						(arc
							(start 0.1778 -0.2794)
							(mid 0.249642 -0.249642)
							(end 0.2794 -0.1778)
						)
						(arc
							(start 0.2794 0.1778)
							(mid 0.249642 0.249642)
							(end 0.1778 0.2794)
						)
					)
					(width 0)
					(fill yes)
				)
			)
		)
		(pad "2" smd custom
			(at 0 0.4445)
			(size 0.1397 0.1397)
			(layers "B.Cu" "B.Mask" "B.Paste")
			(net "COMP_PWR_BTN_N")
			(options
				(clearance outline)
				(anchor circle)
			)
			(primitives
				(gr_poly
					(pts
						(arc
							(start -0.1778 0.2794)
							(mid -0.249642 0.249642)
							(end -0.2794 0.1778)
						)
						(arc
							(start -0.2794 -0.1778)
							(mid -0.249642 -0.249642)
							(end -0.1778 -0.2794)
						)
						(arc
							(start 0.1778 -0.2794)
							(mid 0.249642 -0.249642)
							(end 0.2794 -0.1778)
						)
						(arc
							(start 0.2794 0.1778)
							(mid 0.249642 0.249642)
							(end 0.1778 0.2794)
						)
					)
					(width 0)
					(fill yes)
				)
			)
		)
	)
	(footprint ""
		(layer "B.Cu")
		(at 58.0136 -143.7767 180)
		(property "Reference" "R358"
			(at 0 0 0)
			(layer "B.SilkS")
			(hide yes)
			(effects
				(font
					(size 1.27 1.27)
				)
				(justify mirror)
			)
		)
		(property "Value" "10KR2F-2-GP"
			(at -0.064008 -3.993896 180)
			(unlocked yes)
			(layer "B.Fab")
			(hide yes)
			(effects
				(font
					(size 1.016 1.016)
					(thickness 0.1524)
				)
				(justify mirror)
			)
		)
		(property "Device Type" "R402H16"
			(at -0.064008 -5.517896 180)
			(unlocked yes)
			(layer "B.Fab")
			(hide yes)
			(effects
				(font
					(size 1.016 1.016)
					(thickness 0.1524)
				)
				(justify mirror)
			)
		)
		(duplicate_pad_numbers_are_jumpers no)
		(fp_line
			(start 0.508 -0.9398)
			(end 0.508 0.9398)
			(stroke
				(width 0.1524)
				(type default)
			)
			(layer "B.SilkS")
		)
		(fp_line
			(start -0.508 -0.9398)
			(end 0.508 -0.9398)
			(stroke
				(width 0.1524)
				(type default)
			)
			(layer "B.SilkS")
		)
		(fp_rect
			(start 0.508 0.9398)
			(end -0.508 -0.9398)
			(stroke
				(width 0)
				(type default)
			)
			(fill no)
			(layer "B.CrtYd")
		)
		(fp_rect
			(start 0.508 0.9398)
			(end -0.508 -0.9398)
			(stroke
				(width 0)
				(type default)
			)
			(fill no)
			(layer "B.Fab")
		)
		(pad "1" smd custom
			(at 0 -0.4445)
			(size 0.1397 0.1397)
			(layers "B.Cu" "B.Mask" "B.Paste")
			(net "P3V3_STBY")
			(options
				(clearance outline)
				(anchor circle)
			)
			(primitives
				(gr_poly
					(pts
						(arc
							(start -0.1778 0.2794)
							(mid -0.249642 0.249642)
							(end -0.2794 0.1778)
						)
						(arc
							(start -0.2794 -0.1778)
							(mid -0.249642 -0.249642)
							(end -0.1778 -0.2794)
						)
						(arc
							(start 0.1778 -0.2794)
							(mid 0.249642 -0.249642)
							(end 0.2794 -0.1778)
						)
						(arc
							(start 0.2794 0.1778)
							(mid 0.249642 0.249642)
							(end 0.1778 0.2794)
						)
					)
					(width 0)
					(fill yes)
				)
			)
		)
		(pad "2" smd custom
			(at 0 0.4445)
			(size 0.1397 0.1397)
			(layers "B.Cu" "B.Mask" "B.Paste")
			(net "JTAG_BMC_TDI")
			(options
				(clearance outline)
				(anchor circle)
			)
			(primitives
				(gr_poly
					(pts
						(arc
							(start -0.1778 0.2794)
							(mid -0.249642 0.249642)
							(end -0.2794 0.1778)
						)
						(arc
							(start -0.2794 -0.1778)
							(mid -0.249642 -0.249642)
							(end -0.1778 -0.2794)
						)
						(arc
							(start 0.1778 -0.2794)
							(mid 0.249642 -0.249642)
							(end 0.2794 -0.1778)
						)
						(arc
							(start 0.2794 0.1778)
							(mid 0.249642 0.249642)
							(end 0.1778 0.2794)
						)
					)
					(width 0)
					(fill yes)
				)
			)
		)
	)
	(footprint ""
		(layer "B.Cu")
		(at 181.04612 -81.44256)
		(property "Reference" "L20"
			(at 0 0 0)
			(layer "B.SilkS")
			(hide yes)
			(effects
				(font
					(size 1.27 1.27)
				)
				(justify mirror)
			)
		)
		(property "Value" "MPZ2012S300AT-GP"
			(at 0 -4.2418 0)
			(unlocked yes)
			(layer "B.Fab")
			(hide yes)
			(effects
				(font
					(size 1.016 1.016)
					(thickness 0.1524)
				)
				(justify mirror)
			)
		)
		(property "Device Type" "L805H42"
			(at 0 -5.7912 0)
			(unlocked yes)
			(layer "B.Fab")
			(hide yes)
			(effects
				(font
					(size 1.016 1.016)
					(thickness 0.1524)
				)
				(justify mirror)
			)
		)
		(duplicate_pad_numbers_are_jumpers no)
		(fp_line
			(start -0.889 -1.7018)
			(end -0.889 1.7018)
			(stroke
				(width 0.1524)
				(type default)
			)
			(layer "B.SilkS")
		)
		(fp_line
			(start -0.889 1.7018)
			(end 0.889 1.7018)
			(stroke
				(width 0.1524)
				(type default)
			)
			(layer "B.SilkS")
		)
		(fp_line
			(start 0.889 -1.7018)
			(end -0.889 -1.7018)
			(stroke
				(width 0.1524)
				(type default)
			)
			(layer "B.SilkS")
		)
		(fp_line
			(start 0.889 1.7018)
			(end 0.889 -1.7018)
			(stroke
				(width 0.1524)
				(type default)
			)
			(layer "B.SilkS")
		)
		(fp_rect
			(start 0.9652 1.778)
			(end -0.9652 -1.778)
			(stroke
				(width 0)
				(type default)
			)
			(fill no)
			(layer "B.CrtYd")
		)
		(fp_rect
			(start 0.9652 1.778)
			(end -0.9652 -1.778)
			(stroke
				(width 0)
				(type default)
			)
			(fill no)
			(layer "B.Fab")
		)
		(pad "1" smd rect
			(at 0 -0.9652 180)
			(size 1.397 1.143)
			(layers "B.Cu" "B.Mask" "B.Paste")
			(net "P0V975")
		)
		(pad "2" smd rect
			(at 0 0.9652 180)
			(size 1.397 1.143)
			(layers "B.Cu" "B.Mask" "B.Paste")
			(net "PCE_AVDD")
		)
	)
	(footprint ""
		(layer "B.Cu")
		(at 43.485308 -159.975804 90)
		(property "Reference" "R697"
			(at 0 0 90)
			(layer "B.SilkS")
			(hide yes)
			(effects
				(font
					(size 1.27 1.27)
				)
				(justify mirror)
			)
		)
		(property "Value" "4K7R2F-GP"
			(at -0.064008 -3.993896 90)
			(unlocked yes)
			(layer "B.Fab")
			(hide yes)
			(effects
				(font
					(size 1.016 1.016)
					(thickness 0.1524)
				)
				(justify mirror)
			)
		)
		(property "Device Type" "R402H16"
			(at -0.064008 -5.517896 90)
			(unlocked yes)
			(layer "B.Fab")
			(hide yes)
			(effects
				(font
					(size 1.016 1.016)
					(thickness 0.1524)
				)
				(justify mirror)
			)
		)
		(duplicate_pad_numbers_are_jumpers no)
		(fp_line
			(start 0.508 -0.9398)
			(end 0.508 0.9398)
			(stroke
				(width 0.1524)
				(type default)
			)
			(layer "B.SilkS")
		)
		(fp_line
			(start -0.508 -0.9398)
			(end 0.508 -0.9398)
			(stroke
				(width 0.1524)
				(type default)
			)
			(layer "B.SilkS")
		)
		(fp_rect
			(start 0.508 0.9398)
			(end -0.508 -0.9398)
			(stroke
				(width 0)
				(type default)
			)
			(fill no)
			(layer "B.CrtYd")
		)
		(fp_rect
			(start 0.508 0.9398)
			(end -0.508 -0.9398)
			(stroke
				(width 0)
				(type default)
			)
			(fill no)
			(layer "B.Fab")
		)
		(pad "1" smd custom
			(at 0 -0.4445 270)
			(size 0.1397 0.1397)
			(layers "B.Cu" "B.Mask" "B.Paste")
			(net "P3V3_STBY")
			(options
				(clearance outline)
				(anchor circle)
			)
			(primitives
				(gr_poly
					(pts
						(arc
							(start -0.1778 0.2794)
							(mid -0.249642 0.249642)
							(end -0.2794 0.1778)
						)
						(arc
							(start -0.2794 -0.1778)
							(mid -0.249642 -0.249642)
							(end -0.1778 -0.2794)
						)
						(arc
							(start 0.1778 -0.2794)
							(mid 0.249642 -0.249642)
							(end 0.2794 -0.1778)
						)
						(arc
							(start 0.2794 0.1778)
							(mid 0.249642 0.249642)
							(end 0.1778 0.2794)
						)
					)
					(width 0)
					(fill yes)
				)
			)
		)
		(pad "2" smd custom
			(at 0 0.4445 270)
			(size 0.1397 0.1397)
			(layers "B.Cu" "B.Mask" "B.Paste")
			(net "PCIE_WAKE_N")
			(options
				(clearance outline)
				(anchor circle)
			)
			(primitives
				(gr_poly
					(pts
						(arc
							(start -0.1778 0.2794)
							(mid -0.249642 0.249642)
							(end -0.2794 0.1778)
						)
						(arc
							(start -0.2794 -0.1778)
							(mid -0.249642 -0.249642)
							(end -0.1778 -0.2794)
						)
						(arc
							(start 0.1778 -0.2794)
							(mid 0.249642 -0.249642)
							(end 0.2794 -0.1778)
						)
						(arc
							(start 0.2794 0.1778)
							(mid 0.249642 0.249642)
							(end 0.1778 0.2794)
						)
					)
					(width 0)
					(fill yes)
				)
			)
		)
	)
	(footprint ""
		(layer "B.Cu")
		(at 38.227 -126.51232)
		(property "Reference" "R348"
			(at 0 0 0)
			(layer "B.SilkS")
			(hide yes)
			(effects
				(font
					(size 1.27 1.27)
				)
				(justify mirror)
			)
		)
		(property "Value" "0R2J-2-GP"
			(at -0.064008 -3.993896 0)
			(unlocked yes)
			(layer "B.Fab")
			(hide yes)
			(effects
				(font
					(size 1.016 1.016)
					(thickness 0.1524)
				)
				(justify mirror)
			)
		)
		(property "Device Type" "R402H16"
			(at -0.064008 -5.517896 0)
			(unlocked yes)
			(layer "B.Fab")
			(hide yes)
			(effects
				(font
					(size 1.016 1.016)
					(thickness 0.1524)
				)
				(justify mirror)
			)
		)
		(duplicate_pad_numbers_are_jumpers no)
		(fp_line
			(start -0.508 -0.9398)
			(end 0.508 -0.9398)
			(stroke
				(width 0.1524)
				(type default)
			)
			(layer "B.SilkS")
		)
		(fp_line
			(start 0.508 -0.9398)
			(end 0.508 0.9398)
			(stroke
				(width 0.1524)
				(type default)
			)
			(layer "B.SilkS")
		)
		(fp_rect
			(start 0.508 0.9398)
			(end -0.508 -0.9398)
			(stroke
				(width 0)
				(type default)
			)
			(fill no)
			(layer "B.CrtYd")
		)
		(fp_rect
			(start 0.508 0.9398)
			(end -0.508 -0.9398)
			(stroke
				(width 0)
				(type default)
			)
			(fill no)
			(layer "B.Fab")
		)
		(pad "1" smd custom
			(at 0 -0.4445 180)
			(size 0.1397 0.1397)
			(layers "B.Cu" "B.Mask" "B.Paste")
			(net "BMC_EXTRST_N")
			(options
				(clearance outline)
				(anchor circle)
			)
			(primitives
				(gr_poly
					(pts
						(arc
							(start -0.1778 0.2794)
							(mid -0.249642 0.249642)
							(end -0.2794 0.1778)
						)
						(arc
							(start -0.2794 -0.1778)
							(mid -0.249642 -0.249642)
							(end -0.1778 -0.2794)
						)
						(arc
							(start 0.1778 -0.2794)
							(mid 0.249642 -0.249642)
							(end 0.2794 -0.1778)
						)
						(arc
							(start 0.2794 0.1778)
							(mid 0.249642 0.249642)
							(end 0.1778 0.2794)
						)
					)
					(width 0)
					(fill yes)
				)
			)
		)
		(pad "2" smd custom
			(at 0 0.4445 180)
			(size 0.1397 0.1397)
			(layers "B.Cu" "B.Mask" "B.Paste")
			(net "RST_BMC_EXTRST_N_1")
			(options
				(clearance outline)
				(anchor circle)
			)
			(primitives
				(gr_poly
					(pts
						(arc
							(start -0.1778 0.2794)
							(mid -0.249642 0.249642)
							(end -0.2794 0.1778)
						)
						(arc
							(start -0.2794 -0.1778)
							(mid -0.249642 -0.249642)
							(end -0.1778 -0.2794)
						)
						(arc
							(start 0.1778 -0.2794)
							(mid 0.249642 -0.249642)
							(end 0.2794 -0.1778)
						)
						(arc
							(start 0.2794 0.1778)
							(mid 0.249642 0.249642)
							(end 0.1778 0.2794)
						)
					)
					(width 0)
					(fill yes)
				)
			)
		)
	)
)
